(kicad_pcb
	(version 20260206)
	(generator "pcbnew")
	(generator_version "10.0")
	(general
		(thickness 1.6)
		(legacy_teardrops no)
	)
	(paper "A4")
	(title_block
		(title "04192023_DAF0TMB3IC0_F0TG_MB_C_brd_V02_OCP.brd")
		(comment 1 "Grand Teton / footprints 2879-2884 of 8354")
	)
	(layers
		(0 "F.Cu" signal "TOP")
		(4 "In1.Cu" signal "GND")
		(6 "In2.Cu" signal "IN1")
		(8 "In3.Cu" signal "GND1")
		(10 "In4.Cu" signal "IN2")
		(12 "In5.Cu" signal "GND2")
		(14 "In6.Cu" signal "IN3")
		(16 "In7.Cu" signal "GND3")
		(18 "In8.Cu" signal "VCC")
		(20 "In9.Cu" signal "VCC1")
		(22 "In10.Cu" signal "GND4")
		(24 "In11.Cu" signal "IN4")
		(26 "In12.Cu" signal "GND5")
		(28 "In13.Cu" signal "IN5")
		(30 "In14.Cu" signal "GND6")
		(32 "In15.Cu" signal "IN6")
		(34 "In16.Cu" signal "GND7")
		(2 "B.Cu" signal "BOTTOM")
		(9 "F.Adhes" user "F.Adhesive")
		(11 "B.Adhes" user "B.Adhesive")
		(13 "F.Paste" user "Package Geometry/Pastemask Top")
		(15 "B.Paste" user "Package Geometry/Pastemask Bottom")
		(5 "F.SilkS" user "Ref Des/Silkscreen Top")
		(7 "B.SilkS" user "Ref Des/Silkscreen Bottom")
		(1 "F.Mask" user "Board Geometry/Soldermask Top")
		(3 "B.Mask" user "Board Geometry/Soldermask Bottom")
		(17 "Dwgs.User" user "User.Drawings")
		(19 "Cmts.User" user "User.Comments")
		(21 "Eco1.User" user "User.Eco1")
		(23 "Eco2.User" user "User.Eco2")
		(25 "Edge.Cuts" user "Board Geometry/Outline")
		(27 "Margin" user)
		(31 "F.CrtYd" user "Package Geometry/Place Bound Top")
		(29 "B.CrtYd" user "Package Geometry/Place Bound Bottom")
		(35 "F.Fab" user "Ref Des/Assembly Top")
		(33 "B.Fab" user "Ref Des/Assembly Bottom")
	)
	(footprint ""
		(layer "F.Cu")
		(at 57.17286 -39.36238 90)
		(property "Reference" "R1520"
			(at 0 0 90)
			(layer "F.SilkS")
			(hide yes)
			(effects
				(font
					(size 1.27 1.27)
				)
			)
		)
		(property "Value" ""
			(at 0 0 90)
			(layer "F.Fab")
			(effects
				(font
					(size 1.27 1.27)
				)
			)
		)
		(duplicate_pad_numbers_are_jumpers no)
		(fp_line
			(start 0.7874 -0.4064)
			(end 0.7874 0.4064)
			(stroke
				(width 0.1524)
				(type default)
			)
			(layer "F.SilkS")
		)
		(fp_line
			(start -0.7874 -0.4064)
			(end 0.7874 -0.4064)
			(stroke
				(width 0.1524)
				(type default)
			)
			(layer "F.SilkS")
		)
		(fp_line
			(start 0.7874 0.4064)
			(end -0.7874 0.4064)
			(stroke
				(width 0.1524)
				(type default)
			)
			(layer "F.SilkS")
		)
		(fp_line
			(start -0.7874 0.4064)
			(end -0.7874 -0.4064)
			(stroke
				(width 0.1524)
				(type default)
			)
			(layer "F.SilkS")
		)
		(fp_line
			(start -0.12065 -0.305054)
			(end -0.12065 -0.2794)
			(stroke
				(width 0.1)
				(type default)
			)
			(layer "F.Fab")
		)
		(fp_line
			(start -0.67945 -0.305054)
			(end -0.12065 -0.305054)
			(stroke
				(width 0.1)
				(type default)
			)
			(layer "F.Fab")
		)
		(fp_line
			(start 0.67945 -0.3048)
			(end 0.67945 0.3048)
			(stroke
				(width 0.1)
				(type default)
			)
			(layer "F.Fab")
		)
		(fp_line
			(start 0.12065 -0.3048)
			(end 0.67945 -0.3048)
			(stroke
				(width 0.1)
				(type default)
			)
			(layer "F.Fab")
		)
		(fp_line
			(start 0.12065 -0.2794)
			(end 0.12065 -0.3048)
			(stroke
				(width 0.1)
				(type default)
			)
			(layer "F.Fab")
		)
		(fp_line
			(start -0.12065 -0.2794)
			(end 0.12065 -0.2794)
			(stroke
				(width 0.1)
				(type default)
			)
			(layer "F.Fab")
		)
		(fp_line
			(start 0.120396 0.2794)
			(end -0.12065 0.2794)
			(stroke
				(width 0.1)
				(type default)
			)
			(layer "F.Fab")
		)
		(fp_line
			(start -0.12065 0.2794)
			(end -0.12065 0.3048)
			(stroke
				(width 0.1)
				(type default)
			)
			(layer "F.Fab")
		)
		(fp_line
			(start 0.67945 0.3048)
			(end 0.120396 0.3048)
			(stroke
				(width 0.1)
				(type default)
			)
			(layer "F.Fab")
		)
		(fp_line
			(start 0.120396 0.3048)
			(end 0.120396 0.2794)
			(stroke
				(width 0.1)
				(type default)
			)
			(layer "F.Fab")
		)
		(fp_line
			(start -0.12065 0.3048)
			(end -0.67945 0.3048)
			(stroke
				(width 0.1)
				(type default)
			)
			(layer "F.Fab")
		)
		(fp_line
			(start -0.67945 0.3048)
			(end -0.67945 -0.305054)
			(stroke
				(width 0.1)
				(type default)
			)
			(layer "F.Fab")
		)
		(pad "1" smd circle
			(at -0.40005 0 90)
			(size 0 0)
			(layers "F.Cu" "F.Mask" "F.Paste")
			(net "P12V_OCP_V3_2_BUF_EN_R")
		)
		(pad "2" smd circle
			(at 0.40005 0 90)
			(size 0 0)
			(layers "F.Cu" "F.Mask" "F.Paste")
			(net "P3V3_OCP_EN_2_R")
		)
	)
	(footprint ""
		(layer "F.Cu")
		(at 417.86937 -353.77628 90)
		(property "Reference" "PR413"
			(at 0 0 90)
			(layer "F.SilkS")
			(hide yes)
			(effects
				(font
					(size 1.27 1.27)
				)
			)
		)
		(property "Value" ""
			(at 0 0 90)
			(layer "F.Fab")
			(effects
				(font
					(size 1.27 1.27)
				)
			)
		)
		(duplicate_pad_numbers_are_jumpers no)
		(fp_line
			(start 0.7874 -0.4064)
			(end 0.7874 0.4064)
			(stroke
				(width 0.1524)
				(type default)
			)
			(layer "F.SilkS")
		)
		(fp_line
			(start -0.7874 -0.4064)
			(end 0.7874 -0.4064)
			(stroke
				(width 0.1524)
				(type default)
			)
			(layer "F.SilkS")
		)
		(fp_line
			(start 0.7874 0.4064)
			(end -0.7874 0.4064)
			(stroke
				(width 0.1524)
				(type default)
			)
			(layer "F.SilkS")
		)
		(fp_line
			(start -0.7874 0.4064)
			(end -0.7874 -0.4064)
			(stroke
				(width 0.1524)
				(type default)
			)
			(layer "F.SilkS")
		)
		(fp_line
			(start -0.12065 -0.305054)
			(end -0.12065 -0.2794)
			(stroke
				(width 0.1)
				(type default)
			)
			(layer "F.Fab")
		)
		(fp_line
			(start -0.67945 -0.305054)
			(end -0.12065 -0.305054)
			(stroke
				(width 0.1)
				(type default)
			)
			(layer "F.Fab")
		)
		(fp_line
			(start 0.67945 -0.3048)
			(end 0.67945 0.3048)
			(stroke
				(width 0.1)
				(type default)
			)
			(layer "F.Fab")
		)
		(fp_line
			(start 0.12065 -0.3048)
			(end 0.67945 -0.3048)
			(stroke
				(width 0.1)
				(type default)
			)
			(layer "F.Fab")
		)
		(fp_line
			(start 0.12065 -0.2794)
			(end 0.12065 -0.3048)
			(stroke
				(width 0.1)
				(type default)
			)
			(layer "F.Fab")
		)
		(fp_line
			(start -0.12065 -0.2794)
			(end 0.12065 -0.2794)
			(stroke
				(width 0.1)
				(type default)
			)
			(layer "F.Fab")
		)
		(fp_line
			(start 0.120396 0.2794)
			(end -0.12065 0.2794)
			(stroke
				(width 0.1)
				(type default)
			)
			(layer "F.Fab")
		)
		(fp_line
			(start -0.12065 0.2794)
			(end -0.12065 0.3048)
			(stroke
				(width 0.1)
				(type default)
			)
			(layer "F.Fab")
		)
		(fp_line
			(start 0.67945 0.3048)
			(end 0.120396 0.3048)
			(stroke
				(width 0.1)
				(type default)
			)
			(layer "F.Fab")
		)
		(fp_line
			(start 0.120396 0.3048)
			(end 0.120396 0.2794)
			(stroke
				(width 0.1)
				(type default)
			)
			(layer "F.Fab")
		)
		(fp_line
			(start -0.12065 0.3048)
			(end -0.67945 0.3048)
			(stroke
				(width 0.1)
				(type default)
			)
			(layer "F.Fab")
		)
		(fp_line
			(start -0.67945 0.3048)
			(end -0.67945 -0.305054)
			(stroke
				(width 0.1)
				(type default)
			)
			(layer "F.Fab")
		)
		(pad "1" smd circle
			(at -0.40005 0 90)
			(size 0 0)
			(layers "F.Cu" "F.Mask" "F.Paste")
			(net "PVDD11_S3_P0_PVCC")
		)
		(pad "2" smd circle
			(at 0.40005 0 90)
			(size 0 0)
			(layers "F.Cu" "F.Mask" "F.Paste")
			(net "P3V3_AUX")
		)
	)
	(footprint ""
		(layer "F.Cu")
		(at 449.650612 -23.594314 180)
		(property "Reference" "PC2085"
			(at 0 0 180)
			(layer "F.SilkS")
			(hide yes)
			(effects
				(font
					(size 1.27 1.27)
				)
			)
		)
		(property "Value" ""
			(at 0 0 180)
			(layer "F.Fab")
			(effects
				(font
					(size 1.27 1.27)
				)
			)
		)
		(duplicate_pad_numbers_are_jumpers no)
		(fp_line
			(start 0.7874 0.4064)
			(end -0.7874 0.4064)
			(stroke
				(width 0.1524)
				(type default)
			)
			(layer "F.SilkS")
		)
		(fp_line
			(start 0.7874 -0.4064)
			(end 0.7874 0.4064)
			(stroke
				(width 0.1524)
				(type default)
			)
			(layer "F.SilkS")
		)
		(fp_line
			(start -0.7874 0.4064)
			(end -0.7874 -0.4064)
			(stroke
				(width 0.1524)
				(type default)
			)
			(layer "F.SilkS")
		)
		(fp_line
			(start -0.7874 -0.4064)
			(end 0.7874 -0.4064)
			(stroke
				(width 0.1524)
				(type default)
			)
			(layer "F.SilkS")
		)
		(fp_line
			(start 0.67945 0.3048)
			(end 0.120396 0.3048)
			(stroke
				(width 0.1)
				(type default)
			)
			(layer "F.Fab")
		)
		(fp_line
			(start 0.67945 -0.3048)
			(end 0.67945 0.3048)
			(stroke
				(width 0.1)
				(type default)
			)
			(layer "F.Fab")
		)
		(fp_line
			(start 0.12065 -0.2794)
			(end 0.12065 -0.3048)
			(stroke
				(width 0.1)
				(type default)
			)
			(layer "F.Fab")
		)
		(fp_line
			(start 0.12065 -0.3048)
			(end 0.67945 -0.3048)
			(stroke
				(width 0.1)
				(type default)
			)
			(layer "F.Fab")
		)
		(fp_line
			(start 0.120396 0.3048)
			(end 0.120396 0.2794)
			(stroke
				(width 0.1)
				(type default)
			)
			(layer "F.Fab")
		)
		(fp_line
			(start 0.120396 0.2794)
			(end -0.12065 0.2794)
			(stroke
				(width 0.1)
				(type default)
			)
			(layer "F.Fab")
		)
		(fp_line
			(start -0.12065 0.3048)
			(end -0.67945 0.3048)
			(stroke
				(width 0.1)
				(type default)
			)
			(layer "F.Fab")
		)
		(fp_line
			(start -0.12065 0.2794)
			(end -0.12065 0.3048)
			(stroke
				(width 0.1)
				(type default)
			)
			(layer "F.Fab")
		)
		(fp_line
			(start -0.12065 -0.2794)
			(end 0.12065 -0.2794)
			(stroke
				(width 0.1)
				(type default)
			)
			(layer "F.Fab")
		)
		(fp_line
			(start -0.12065 -0.305054)
			(end -0.12065 -0.2794)
			(stroke
				(width 0.1)
				(type default)
			)
			(layer "F.Fab")
		)
		(fp_line
			(start -0.67945 0.3048)
			(end -0.67945 -0.305054)
			(stroke
				(width 0.1)
				(type default)
			)
			(layer "F.Fab")
		)
		(fp_line
			(start -0.67945 -0.305054)
			(end -0.12065 -0.305054)
			(stroke
				(width 0.1)
				(type default)
			)
			(layer "F.Fab")
		)
		(pad "1" smd circle
			(at -0.40005 0 180)
			(size 0 0)
			(layers "F.Cu" "F.Mask" "F.Paste")
			(net "P12V_OCP_VCC_1")
		)
		(pad "2" smd circle
			(at 0.40005 0 180)
			(size 0 0)
			(layers "F.Cu" "F.Mask" "F.Paste")
			(net "GND")
		)
	)
	(footprint ""
		(layer "F.Cu")
		(at 445.157098 -93.484192 180)
		(property "Reference" "R3627"
			(at 0 0 180)
			(layer "F.SilkS")
			(hide yes)
			(effects
				(font
					(size 1.27 1.27)
				)
			)
		)
		(property "Value" ""
			(at 0 0 180)
			(layer "F.Fab")
			(effects
				(font
					(size 1.27 1.27)
				)
			)
		)
		(duplicate_pad_numbers_are_jumpers no)
		(fp_line
			(start 0.7874 0.4064)
			(end -0.7874 0.4064)
			(stroke
				(width 0.1524)
				(type default)
			)
			(layer "F.SilkS")
		)
		(fp_line
			(start 0.7874 -0.4064)
			(end 0.7874 0.4064)
			(stroke
				(width 0.1524)
				(type default)
			)
			(layer "F.SilkS")
		)
		(fp_line
			(start -0.7874 0.4064)
			(end -0.7874 -0.4064)
			(stroke
				(width 0.1524)
				(type default)
			)
			(layer "F.SilkS")
		)
		(fp_line
			(start -0.7874 -0.4064)
			(end 0.7874 -0.4064)
			(stroke
				(width 0.1524)
				(type default)
			)
			(layer "F.SilkS")
		)
		(fp_line
			(start 0.67945 0.3048)
			(end 0.120396 0.3048)
			(stroke
				(width 0.1)
				(type default)
			)
			(layer "F.Fab")
		)
		(fp_line
			(start 0.67945 -0.3048)
			(end 0.67945 0.3048)
			(stroke
				(width 0.1)
				(type default)
			)
			(layer "F.Fab")
		)
		(fp_line
			(start 0.12065 -0.2794)
			(end 0.12065 -0.3048)
			(stroke
				(width 0.1)
				(type default)
			)
			(layer "F.Fab")
		)
		(fp_line
			(start 0.12065 -0.3048)
			(end 0.67945 -0.3048)
			(stroke
				(width 0.1)
				(type default)
			)
			(layer "F.Fab")
		)
		(fp_line
			(start 0.120396 0.3048)
			(end 0.120396 0.2794)
			(stroke
				(width 0.1)
				(type default)
			)
			(layer "F.Fab")
		)
		(fp_line
			(start 0.120396 0.2794)
			(end -0.12065 0.2794)
			(stroke
				(width 0.1)
				(type default)
			)
			(layer "F.Fab")
		)
		(fp_line
			(start -0.12065 0.3048)
			(end -0.67945 0.3048)
			(stroke
				(width 0.1)
				(type default)
			)
			(layer "F.Fab")
		)
		(fp_line
			(start -0.12065 0.2794)
			(end -0.12065 0.3048)
			(stroke
				(width 0.1)
				(type default)
			)
			(layer "F.Fab")
		)
		(fp_line
			(start -0.12065 -0.2794)
			(end 0.12065 -0.2794)
			(stroke
				(width 0.1)
				(type default)
			)
			(layer "F.Fab")
		)
		(fp_line
			(start -0.12065 -0.305054)
			(end -0.12065 -0.2794)
			(stroke
				(width 0.1)
				(type default)
			)
			(layer "F.Fab")
		)
		(fp_line
			(start -0.67945 0.3048)
			(end -0.67945 -0.305054)
			(stroke
				(width 0.1)
				(type default)
			)
			(layer "F.Fab")
		)
		(fp_line
			(start -0.67945 -0.305054)
			(end -0.12065 -0.305054)
			(stroke
				(width 0.1)
				(type default)
			)
			(layer "F.Fab")
		)
		(pad "1" smd circle
			(at -0.40005 0 180)
			(size 0 0)
			(layers "F.Cu" "F.Mask" "F.Paste")
			(net "P3V3_AUX")
		)
		(pad "2" smd circle
			(at 0.40005 0 180)
			(size 0 0)
			(layers "F.Cu" "F.Mask" "F.Paste")
			(net "INA230_1_A0")
		)
	)
	(footprint ""
		(layer "F.Cu")
		(at 311.541922 -33.715706)
		(property "Reference" "R3863"
			(at 0 0 0)
			(layer "F.SilkS")
			(hide yes)
			(effects
				(font
					(size 1.27 1.27)
				)
			)
		)
		(property "Value" ""
			(at 0 0 0)
			(layer "F.Fab")
			(effects
				(font
					(size 1.27 1.27)
				)
			)
		)
		(duplicate_pad_numbers_are_jumpers no)
		(fp_line
			(start -0.7874 -0.4064)
			(end 0.7874 -0.4064)
			(stroke
				(width 0.1524)
				(type default)
			)
			(layer "F.SilkS")
		)
		(fp_line
			(start -0.7874 0.4064)
			(end -0.7874 -0.4064)
			(stroke
				(width 0.1524)
				(type default)
			)
			(layer "F.SilkS")
		)
		(fp_line
			(start 0.7874 -0.4064)
			(end 0.7874 0.4064)
			(stroke
				(width 0.1524)
				(type default)
			)
			(layer "F.SilkS")
		)
		(fp_line
			(start 0.7874 0.4064)
			(end -0.7874 0.4064)
			(stroke
				(width 0.1524)
				(type default)
			)
			(layer "F.SilkS")
		)
		(fp_line
			(start -0.67945 -0.305054)
			(end -0.12065 -0.305054)
			(stroke
				(width 0.1)
				(type default)
			)
			(layer "F.Fab")
		)
		(fp_line
			(start -0.67945 0.3048)
			(end -0.67945 -0.305054)
			(stroke
				(width 0.1)
				(type default)
			)
			(layer "F.Fab")
		)
		(fp_line
			(start -0.12065 -0.305054)
			(end -0.12065 -0.2794)
			(stroke
				(width 0.1)
				(type default)
			)
			(layer "F.Fab")
		)
		(fp_line
			(start -0.12065 -0.2794)
			(end 0.12065 -0.2794)
			(stroke
				(width 0.1)
				(type default)
			)
			(layer "F.Fab")
		)
		(fp_line
			(start -0.12065 0.2794)
			(end -0.12065 0.3048)
			(stroke
				(width 0.1)
				(type default)
			)
			(layer "F.Fab")
		)
		(fp_line
			(start -0.12065 0.3048)
			(end -0.67945 0.3048)
			(stroke
				(width 0.1)
				(type default)
			)
			(layer "F.Fab")
		)
		(fp_line
			(start 0.120396 0.2794)
			(end -0.12065 0.2794)
			(stroke
				(width 0.1)
				(type default)
			)
			(layer "F.Fab")
		)
		(fp_line
			(start 0.120396 0.3048)
			(end 0.120396 0.2794)
			(stroke
				(width 0.1)
				(type default)
			)
			(layer "F.Fab")
		)
		(fp_line
			(start 0.12065 -0.3048)
			(end 0.67945 -0.3048)
			(stroke
				(width 0.1)
				(type default)
			)
			(layer "F.Fab")
		)
		(fp_line
			(start 0.12065 -0.2794)
			(end 0.12065 -0.3048)
			(stroke
				(width 0.1)
				(type default)
			)
			(layer "F.Fab")
		)
		(fp_line
			(start 0.67945 -0.3048)
			(end 0.67945 0.3048)
			(stroke
				(width 0.1)
				(type default)
			)
			(layer "F.Fab")
		)
		(fp_line
			(start 0.67945 0.3048)
			(end 0.120396 0.3048)
			(stroke
				(width 0.1)
				(type default)
			)
			(layer "F.Fab")
		)
		(pad "1" smd rect
			(at -0.40005 0 180)
			(size 0.4572 0.508)
			(layers "F.Cu" "F.Mask" "F.Paste")
			(net "P12V_OCP_SFF_ISENSE_MAM_MAM")
		)
		(pad "2" smd rect
			(at 0.40005 0 180)
			(size 0.4572 0.508)
			(layers "F.Cu" "F.Mask" "F.Paste")
			(net "P12V_OCP_SFF_ISENSE_MAM")
		)
	)
	(footprint ""
		(layer "F.Cu")
		(at 449.443602 -427.152308)
		(property "Reference" "PC6603"
			(at 0 0 0)
			(layer "F.SilkS")
			(hide yes)
			(effects
				(font
					(size 1.27 1.27)
				)
			)
		)
		(property "Value" ""
			(at 0 0 0)
			(layer "F.Fab")
			(effects
				(font
					(size 1.27 1.27)
				)
			)
		)
		(duplicate_pad_numbers_are_jumpers no)
		(fp_line
			(start -0.7874 -0.4064)
			(end 0.7874 -0.4064)
			(stroke
				(width 0.1524)
				(type default)
			)
			(layer "F.SilkS")
		)
		(fp_line
			(start -0.7874 0.4064)
			(end -0.7874 -0.4064)
			(stroke
				(width 0.1524)
				(type default)
			)
			(layer "F.SilkS")
		)
		(fp_line
			(start 0.7874 -0.4064)
			(end 0.7874 0.4064)
			(stroke
				(width 0.1524)
				(type default)
			)
			(layer "F.SilkS")
		)
		(fp_line
			(start 0.7874 0.4064)
			(end -0.7874 0.4064)
			(stroke
				(width 0.1524)
				(type default)
			)
			(layer "F.SilkS")
		)
		(fp_line
			(start -0.67945 -0.305054)
			(end -0.12065 -0.305054)
			(stroke
				(width 0.1)
				(type default)
			)
			(layer "F.Fab")
		)
		(fp_line
			(start -0.67945 0.3048)
			(end -0.67945 -0.305054)
			(stroke
				(width 0.1)
				(type default)
			)
			(layer "F.Fab")
		)
		(fp_line
			(start -0.12065 -0.305054)
			(end -0.12065 -0.2794)
			(stroke
				(width 0.1)
				(type default)
			)
			(layer "F.Fab")
		)
		(fp_line
			(start -0.12065 -0.2794)
			(end 0.12065 -0.2794)
			(stroke
				(width 0.1)
				(type default)
			)
			(layer "F.Fab")
		)
		(fp_line
			(start -0.12065 0.2794)
			(end -0.12065 0.3048)
			(stroke
				(width 0.1)
				(type default)
			)
			(layer "F.Fab")
		)
		(fp_line
			(start -0.12065 0.3048)
			(end -0.67945 0.3048)
			(stroke
				(width 0.1)
				(type default)
			)
			(layer "F.Fab")
		)
		(fp_line
			(start 0.120396 0.2794)
			(end -0.12065 0.2794)
			(stroke
				(width 0.1)
				(type default)
			)
			(layer "F.Fab")
		)
		(fp_line
			(start 0.120396 0.3048)
			(end 0.120396 0.2794)
			(stroke
				(width 0.1)
				(type default)
			)
			(layer "F.Fab")
		)
		(fp_line
			(start 0.12065 -0.3048)
			(end 0.67945 -0.3048)
			(stroke
				(width 0.1)
				(type default)
			)
			(layer "F.Fab")
		)
		(fp_line
			(start 0.12065 -0.2794)
			(end 0.12065 -0.3048)
			(stroke
				(width 0.1)
				(type default)
			)
			(layer "F.Fab")
		)
		(fp_line
			(start 0.67945 -0.3048)
			(end 0.67945 0.3048)
			(stroke
				(width 0.1)
				(type default)
			)
			(layer "F.Fab")
		)
		(fp_line
			(start 0.67945 0.3048)
			(end 0.120396 0.3048)
			(stroke
				(width 0.1)
				(type default)
			)
			(layer "F.Fab")
		)
		(pad "1" smd circle
			(at -0.40005 0)
			(size 0 0)
			(layers "F.Cu" "F.Mask" "F.Paste")
			(net "P0V9_RETIMER_CPU0_VCC")
		)
		(pad "2" smd circle
			(at 0.40005 0)
			(size 0 0)
			(layers "F.Cu" "F.Mask" "F.Paste")
			(net "GND")
		)
	)
)
